# SCM (Grand Teton) — schematic netlist excerpt (pin names and nets, part order shuffled) for the footprints in the layout excerpt that follows; sources: Cadence DE-HDL packaged netlist, KiCad conversion of 12092022_DA0F0TMDCD0_F0T_Management_Board_D_brd_V3_OCP.brd

C212  Q_CAP  10PF 50V 1% NPO  pkg 0402  page 23 : A = V_VGAVS_BUF ; B = GND
R851  Q_RES  4.7K 1% CHIP  pkg 0402LF  page 27 : A = P3V3_AUX ; B = SMB_BMC_ALERT15_N

(kicad_pcb
	(version 20260206)
	(generator "pcbnew")
	(generator_version "10.0")
	(general
		(thickness 1.6)
		(legacy_teardrops no)
	)
	(paper "A4")
	(title_block
		(title "12092022_DA0F0TMDCD0_F0T_Management_Board_D_brd_V3_OCP.brd")
		(comment 1 "Grand Teton / footprints 1004-1005 of 1440")
	)
	(layers
		(0 "F.Cu" signal "TOP")
		(4 "In1.Cu" signal "GND")
		(6 "In2.Cu" signal "IN1")
		(8 "In3.Cu" signal "GND1")
		(10 "In4.Cu" signal "IN2")
		(12 "In5.Cu" signal "VCC")
		(14 "In6.Cu" signal "VCC1")
		(16 "In7.Cu" signal "IN3")
		(18 "In8.Cu" signal "GND2")
		(20 "In9.Cu" signal "IN4")
		(22 "In10.Cu" signal "GND3")
		(2 "B.Cu" signal "BOTTOM")
		(9 "F.Adhes" user "F.Adhesive")
		(11 "B.Adhes" user "B.Adhesive")
		(13 "F.Paste" user "Package Geometry/Pastemask Top")
		(15 "B.Paste" user "Package Geometry/Pastemask Bottom")
		(5 "F.SilkS" user "Ref Des/Silkscreen Top")
		(7 "B.SilkS" user "Ref Des/Silkscreen Bottom")
		(1 "F.Mask" user "Board Geometry/Soldermask Top")
		(3 "B.Mask" user "Board Geometry/Soldermask Bottom")
		(17 "Dwgs.User" user "User.Drawings")
		(19 "Cmts.User" user "User.Comments")
		(21 "Eco1.User" user "User.Eco1")
		(23 "Eco2.User" user "User.Eco2")
		(25 "Edge.Cuts" user "Board Geometry/Outline")
		(27 "Margin" user)
		(31 "F.CrtYd" user "Package Geometry/Place Bound Top")
		(29 "B.CrtYd" user "Package Geometry/Place Bound Bottom")
		(35 "F.Fab" user "Ref Des/Assembly Top")
		(33 "B.Fab" user "Ref Des/Assembly Bottom")
	)
	(footprint ""
		(layer "B.Cu")
		(at 29.1846 -27.7622)
		(property "Reference" "C212"
			(at 0 0 0)
			(layer "B.SilkS")
			(hide yes)
			(effects
				(font
					(size 1.27 1.27)
				)
				(justify mirror)
			)
		)
		(property "Value" ""
			(at 0 0 0)
			(layer "B.Fab")
			(effects
				(font
					(size 1.27 1.27)
				)
				(justify mirror)
			)
		)
		(duplicate_pad_numbers_are_jumpers no)
		(fp_line
			(start -0.7874 -0.4064)
			(end -0.7874 0.4064)
			(stroke
				(width 0.1524)
				(type default)
			)
			(layer "B.SilkS")
		)
		(fp_line
			(start -0.7874 0.4064)
			(end 0.7874 0.4064)
			(stroke
				(width 0.1524)
				(type default)
			)
			(layer "B.SilkS")
		)
		(fp_line
			(start 0.7874 -0.4064)
			(end -0.7874 -0.4064)
			(stroke
				(width 0.1524)
				(type default)
			)
			(layer "B.SilkS")
		)
		(fp_line
			(start 0.7874 0.4064)
			(end 0.7874 -0.4064)
			(stroke
				(width 0.1524)
				(type default)
			)
			(layer "B.SilkS")
		)
		(fp_line
			(start -0.67945 -0.3048)
			(end -0.67945 0.3048)
			(stroke
				(width 0.1)
				(type default)
			)
			(layer "B.Fab")
		)
		(fp_line
			(start -0.67945 0.3048)
			(end -0.120396 0.3048)
			(stroke
				(width 0.1)
				(type default)
			)
			(layer "B.Fab")
		)
		(fp_line
			(start -0.12065 -0.3048)
			(end -0.67945 -0.3048)
			(stroke
				(width 0.1)
				(type default)
			)
			(layer "B.Fab")
		)
		(fp_line
			(start -0.12065 -0.2794)
			(end -0.12065 -0.3048)
			(stroke
				(width 0.1)
				(type default)
			)
			(layer "B.Fab")
		)
		(fp_line
			(start -0.120396 0.2794)
			(end 0.12065 0.2794)
			(stroke
				(width 0.1)
				(type default)
			)
			(layer "B.Fab")
		)
		(fp_line
			(start -0.120396 0.3048)
			(end -0.120396 0.2794)
			(stroke
				(width 0.1)
				(type default)
			)
			(layer "B.Fab")
		)
		(fp_line
			(start 0.12065 -0.305054)
			(end 0.12065 -0.2794)
			(stroke
				(width 0.1)
				(type default)
			)
			(layer "B.Fab")
		)
		(fp_line
			(start 0.12065 -0.2794)
			(end -0.12065 -0.2794)
			(stroke
				(width 0.1)
				(type default)
			)
			(layer "B.Fab")
		)
		(fp_line
			(start 0.12065 0.2794)
			(end 0.12065 0.3048)
			(stroke
				(width 0.1)
				(type default)
			)
			(layer "B.Fab")
		)
		(fp_line
			(start 0.12065 0.3048)
			(end 0.67945 0.3048)
			(stroke
				(width 0.1)
				(type default)
			)
			(layer "B.Fab")
		)
		(fp_line
			(start 0.67945 -0.305054)
			(end 0.12065 -0.305054)
			(stroke
				(width 0.1)
				(type default)
			)
			(layer "B.Fab")
		)
		(fp_line
			(start 0.67945 0.3048)
			(end 0.67945 -0.305054)
			(stroke
				(width 0.1)
				(type default)
			)
			(layer "B.Fab")
		)
		(pad "1" smd circle
			(at 0.40005 0 180)
			(size 0 0)
			(layers "B.Cu" "B.Mask" "B.Paste")
			(net "V_VGAVS_BUF")
		)
		(pad "2" smd circle
			(at -0.40005 0 180)
			(size 0 0)
			(layers "B.Cu" "B.Mask" "B.Paste")
			(net "GND")
		)
	)
	(footprint ""
		(layer "B.Cu")
		(at 61.996828 -27.875992 90)
		(property "Reference" "R851"
			(at 0 0 90)
			(layer "B.SilkS")
			(hide yes)
			(effects
				(font
					(size 1.27 1.27)
				)
				(justify mirror)
			)
		)
		(property "Value" ""
			(at 0 0 90)
			(layer "B.Fab")
			(effects
				(font
					(size 1.27 1.27)
				)
				(justify mirror)
			)
		)
		(duplicate_pad_numbers_are_jumpers no)
		(fp_line
			(start 0.7874 -0.4064)
			(end -0.7874 -0.4064)
			(stroke
				(width 0.1524)
				(type default)
			)
			(layer "B.SilkS")
		)
		(fp_line
			(start -0.7874 -0.4064)
			(end -0.7874 0.4064)
			(stroke
				(width 0.1524)
				(type default)
			)
			(layer "B.SilkS")
		)
		(fp_line
			(start 0.7874 0.4064)
			(end 0.7874 -0.4064)
			(stroke
				(width 0.1524)
				(type default)
			)
			(layer "B.SilkS")
		)
		(fp_line
			(start -0.7874 0.4064)
			(end 0.7874 0.4064)
			(stroke
				(width 0.1524)
				(type default)
			)
			(layer "B.SilkS")
		)
		(fp_line
			(start 0.67945 -0.305054)
			(end 0.12065 -0.305054)
			(stroke
				(width 0.1)
				(type default)
			)
			(layer "B.Fab")
		)
		(fp_line
			(start 0.12065 -0.305054)
			(end 0.12065 -0.2794)
			(stroke
				(width 0.1)
				(type default)
			)
			(layer "B.Fab")
		)
		(fp_line
			(start -0.12065 -0.3048)
			(end -0.67945 -0.3048)
			(stroke
				(width 0.1)
				(type default)
			)
			(layer "B.Fab")
		)
		(fp_line
			(start -0.67945 -0.3048)
			(end -0.67945 0.3048)
			(stroke
				(width 0.1)
				(type default)
			)
			(layer "B.Fab")
		)
		(fp_line
			(start 0.12065 -0.2794)
			(end -0.12065 -0.2794)
			(stroke
				(width 0.1)
				(type default)
			)
			(layer "B.Fab")
		)
		(fp_line
			(start -0.12065 -0.2794)
			(end -0.12065 -0.3048)
			(stroke
				(width 0.1)
				(type default)
			)
			(layer "B.Fab")
		)
		(fp_line
			(start 0.12065 0.2794)
			(end 0.12065 0.3048)
			(stroke
				(width 0.1)
				(type default)
			)
			(layer "B.Fab")
		)
		(fp_line
			(start -0.120396 0.2794)
			(end 0.12065 0.2794)
			(stroke
				(width 0.1)
				(type default)
			)
			(layer "B.Fab")
		)
		(fp_line
			(start 0.67945 0.3048)
			(end 0.67945 -0.305054)
			(stroke
				(width 0.1)
				(type default)
			)
			(layer "B.Fab")
		)
		(fp_line
			(start 0.12065 0.3048)
			(end 0.67945 0.3048)
			(stroke
				(width 0.1)
				(type default)
			)
			(layer "B.Fab")
		)
		(fp_line
			(start -0.120396 0.3048)
			(end -0.120396 0.2794)
			(stroke
				(width 0.1)
				(type default)
			)
			(layer "B.Fab")
		)
		(fp_line
			(start -0.67945 0.3048)
			(end -0.120396 0.3048)
			(stroke
				(width 0.1)
				(type default)
			)
			(layer "B.Fab")
		)
		(pad "1" smd circle
			(at 0.40005 0 270)
			(size 0 0)
			(layers "B.Cu" "B.Mask" "B.Paste")
			(net "P3V3_AUX")
		)
		(pad "2" smd circle
			(at -0.40005 0 270)
			(size 0 0)
			(layers "B.Cu" "B.Mask" "B.Paste")
			(net "SMB_BMC_ALERT15_N")
		)
	)
)
